# BASEBOARD_FAB2 (Tioga Pass) — schematic netlist excerpt (pin names and nets, part order shuffled) for the footprints in the layout excerpt that follows; sources: Cadence DE-HDL packaged netlist, KiCad conversion of Wiwynn_Tioga_Pass_MB.brd

J1G1  SCONN288_H44441004  SCONN  pkg PIP  page 77
  \12v\(1)  = P12V_NVDIMM_GHJ
  VSS(93)  = GND
  DQ(4)  = M_G_DQ<5>
  VSS(92)  = GND
  DQ(0)  = M_G_DQ<1>
  VSS(91)  = GND
  DQS9P  = M_G_DQS_DP<9>
  DQS9N  = M_G_DQS_DN<9>
  VSS(90)  = GND
  DQ(6)  = M_G_DQ<7>
  VSS(89)  = GND
  DQ(2)  = M_G_DQ<3>
  VSS(88)  = GND
  DQ(12)  = M_G_DQ<13>
  VSS(87)  = GND
  DQ(8)  = M_G_DQ<9>
  VSS(86)  = GND
  DQS10P  = M_G_DQS_DP<10>
  DQS10N  = M_G_DQS_DN<10>
  VSS(85)  = GND
  DQ(14)  = M_G_DQ<15>
  VSS(84)  = GND
  DQ(10)  = M_G_DQ<11>
  VSS(83)  = GND
  DQ(20)  = M_G_DQ<21>
  VSS(82)  = GND
  DQ(16)  = M_G_DQ<17>
  VSS(81)  = GND
  DQS11P  = M_G_DQS_DP<11>
  DQS11N  = M_G_DQS_DN<11>
  VSS(80)  = GND
  DQ(22)  = M_G_DQ<23>
  VSS(79)  = GND
  DQ(18)  = M_G_DQ<19>
  VSS(78)  = GND
  DQ(28)  = M_G_DQ<29>
  VSS(77)  = GND
  DQ(24)  = M_G_DQ<25>
  VSS(76)  = GND
  DQS12P  = M_G_DQS_DP<12>
  DQS12N  = M_G_DQS_DN<12>
  VSS(75)  = GND
  DQ(30)  = M_G_DQ<31>
  VSS(74)  = GND
  DQ(26)  = M_G_DQ<27>
  VSS(73)  = GND
  CB(4)  = M_G_ECC<5>
  VSS(72)  = GND
  CB(0)  = M_G_ECC<1>
  VSS(71)  = GND
  DQS17P  = M_G_DQS_DP<17>
  DQS17N  = M_G_DQS_DN<17>
  VSS(70)  = GND
  CB(6)  = M_G_ECC<7>
  VSS(69)  = GND
  CB(2)  = M_G_ECC<3>
  VSS(68)  = GND
  RESET_N  = M_GHJ_RST_N
  VDD(25)  = PVDDQ_GHJ
  CKE(0)  = M_G_CKE<0>
  VDD(24)  = PVDDQ_GHJ
  ACT_N  = M_G_ACT_N
  BG(0)  = M_G_BG<0>
  VDD(23)  = PVDDQ_GHJ
  A12  = M_G_MA<12>
  A9  = M_G_MA<9>
  VDD(22)  = PVDDQ_GHJ
  A8  = M_G_MA<8>
  A6  = M_G_MA<6>
  VDD(21)  = PVDDQ_GHJ
  A3  = M_G_MA<3>
  A1  = M_G_MA<1>
  VDD(20)  = PVDDQ_GHJ
  CK0P  = M_G_CLK_DP<0>
  CK0N  = M_G_CLK_DN<0>
  VDD(19)  = PVDDQ_GHJ
  VTT(1)  = PVTT_GHJ
  EVENT_N  = FM_DIMM_EVENT_COD_N
  A0  = M_G_MA<0>
  VDD(18)  = PVDDQ_GHJ
  BA(0)  = M_G_BA<0>
  A16_RAS_N  = M_G_MA<16>
  VDD(17)  = PVDDQ_GHJ
  S0_N  = M_G_CS_N<0>
  VDD(16)  = PVDDQ_GHJ
  A15_CAS_N  = M_G_MA<15>
  ODT(0)  = M_G_ODT<0>
  VDD(15)  = PVDDQ_GHJ
  S1_N  = M_G_CS_N<1>
  VDD(14)  = PVDDQ_GHJ
  ODT(1)  = M_G_ODT<1>
  VDD(13)  = PVDDQ_GHJ
  S2_N_C(0)  = M_G_CS_N<2>
  VSS(67)  = GND
  DQ(36)  = M_G_DQ<37>
  VSS(66)  = GND
  DQ(32)  = M_G_DQ<33>
  VSS(65)  = GND
  DQS13P  = M_G_DQS_DP<13>
  DQS13N  = M_G_DQS_DN<13>
  VSS(64)  = GND
  DQ(38)  = M_G_DQ<39>
  VSS(63)  = GND
  DQ(34)  = M_G_DQ<35>
  VSS(62)  = GND
  DQ(44)  = M_G_DQ<45>
  VSS(61)  = GND
  DQ(40)  = M_G_DQ<41>
  VSS(60)  = GND
  DQS14P  = M_G_DQS_DP<14>
  DQS14N  = M_G_DQS_DN<14>
  VSS(59)  = GND
  DQ(46)  = M_G_DQ<47>
  VSS(58)  = GND
  DQ(42)  = M_G_DQ<43>
  VSS(57)  = GND
  DQ(52)  = M_G_DQ<53>
  VSS(56)  = GND
  DQ(48)  = M_G_DQ<49>
  VSS(55)  = GND
  DQS15P  = M_G_DQS_DP<15>
  DQS15N  = M_G_DQS_DN<15>
  VSS(54)  = GND
  DQ(54)  = M_G_DQ<55>
  VSS(53)  = GND
  DQ(50)  = M_G_DQ<51>
  VSS(52)  = GND
  DQ(60)  = M_G_DQ<61>
  VSS(51)  = GND
  DQ(56)  = M_G_DQ<57>
  VSS(50)  = GND
  DQS16P  = M_G_DQS_DP<16>
  DQS16N  = M_G_DQS_DN<16>
  VSS(49)  = GND
  DQ(62)  = M_G_DQ<63>
  VSS(48)  = GND
  DQ(58)  = M_G_DQ<59>
  VSS(47)  = GND
  SA(0)  = GND
  SA(1)  = GND
  SCL  = SMB_DDR_GHJ_VPP_SCL
  VPP(4)  = PVPP_GHJ
  VPP(3)  = PVPP_GHJ
  RFU(2)  = TP_CH_G_DIMM_G0_RFU_2
  \12v\(0)  = P12V_NVDIMM_GHJ
  VREFCA  = M_G_VREF
  VSS(46)  = GND
  DQ(5)  = M_G_DQ<4>
  VSS(45)  = GND
  DQ(1)  = M_G_DQ<0>
  VSS(44)  = GND
  DQS0N  = M_G_DQS_DN<0>
  DQS0P  = M_G_DQS_DP<0>
  VSS(43)  = GND
  DQ(7)  = M_G_DQ<6>
  VSS(42)  = GND
  DQ(3)  = M_G_DQ<2>
  VSS(41)  = GND
  DQ(13)  = M_G_DQ<12>
  VSS(40)  = GND
  DQ(9)  = M_G_DQ<8>
  VSS(39)  = GND
  DQS1N  = M_G_DQS_DN<1>
  DQS1P  = M_G_DQS_DP<1>
  VSS(38)  = GND
  DQ(15)  = M_G_DQ<14>
  VSS(37)  = GND
  DQ(11)  = M_G_DQ<10>
  VSS(36)  = GND
  DQ(21)  = M_G_DQ<20>
  VSS(35)  = GND
  DQ(17)  = M_G_DQ<16>
  VSS(34)  = GND
  DQS2N  = M_G_DQS_DN<2>
  DQS2P  = M_G_DQS_DP<2>
  VSS(33)  = GND
  DQ(23)  = M_G_DQ<22>
  VSS(32)  = GND
  DQ(19)  = M_G_DQ<18>
  VSS(31)  = GND
  DQ(29)  = M_G_DQ<28>
  VSS(30)  = GND
  DQ(25)  = M_G_DQ<24>
  VSS(29)  = GND
  DQS3N  = M_G_DQS_DN<3>
  DQS3P  = M_G_DQS_DP<3>
  VSS(28)  = GND
  DQ(31)  = M_G_DQ<30>
  VSS(27)  = GND
  DQ(27)  = M_G_DQ<26>
  VSS(26)  = GND
  CB(5)  = M_G_ECC<4>
  VSS(25)  = GND
  CB(1)  = M_G_ECC<0>
  VSS(24)  = GND
  DQS8N  = M_G_DQS_DN<8>
  DQS8P  = M_G_DQS_DP<8>
  VSS(23)  = GND
  CB(7)  = M_G_ECC<6>
  VSS(22)  = GND
  CB(3)  = M_G_ECC<2>
  VSS(21)  = GND
  CKE(1)  = M_G_CKE<1>
  VDD(12)  = PVDDQ_GHJ
  RFU(0)  = TP_CH_G_DIMM_G0_RFU_0
  VDD(11)  = PVDDQ_GHJ
  BG(1)  = M_G_BG<1>
  ALERT_N  = M_G_ALERT_N
  VDD(10)  = PVDDQ_GHJ
  A11  = M_G_MA<11>
  A7  = M_G_MA<7>
  VDD(9)  = PVDDQ_GHJ
  A5  = M_G_MA<5>
  A4  = M_G_MA<4>
  VDD(8)  = PVDDQ_GHJ
  A2  = M_G_MA<2>
  VDD(7)  = PVDDQ_GHJ
  CK1P  = M_G_CLK_DP<1>
  CK1N  = M_G_CLK_DN<1>
  VDD(6)  = PVDDQ_GHJ
  VTT(0)  = PVTT_GHJ
  PAR  = M_G_PAR
  VDD(5)  = PVDDQ_GHJ
  BA(1)  = M_G_BA<1>
  A10  = M_G_MA<10>
  VDD(4)  = PVDDQ_GHJ
  RFU(1)  = TP_CH_G_DIMM_G0_RFU_1
  A14_WE_N  = M_G_MA<14>
  VDD(3)  = PVDDQ_GHJ
  SAVE_N_NC  = FM_ADR_COMPLETE_GHJ_N
  VDD(2)  = PVDDQ_GHJ
  A13  = M_G_MA<13>
  VDD(1)  = PVDDQ_GHJ
  A17  = M_G_MA<17>
  C(2)  = M_G_C<2>
  VDD(0)  = PVDDQ_GHJ
  S3_N_C(1)  = M_G_CS_N<3>
  SA(2)  = GND
  VSS(20)  = GND
  DQ(37)  = M_G_DQ<36>
  VSS(19)  = GND
  DQ(33)  = M_G_DQ<32>
  VSS(18)  = GND
  DQS4N  = M_G_DQS_DN<4>
  DQS4P  = M_G_DQS_DP<4>
  VSS(17)  = GND
  DQ(39)  = M_G_DQ<38>
  VSS(16)  = GND
  DQ(35)  = M_G_DQ<34>
  VSS(15)  = GND
  DQ(45)  = M_G_DQ<44>
  VSS(14)  = GND
  DQ(41)  = M_G_DQ<40>
  VSS(13)  = GND
  DQS5N  = M_G_DQS_DN<5>
  DQS5P  = M_G_DQS_DP<5>
  VSS(12)  = GND
  DQ(47)  = M_G_DQ<46>
  VSS(11)  = GND
  DQ(43)  = M_G_DQ<42>
  VSS(10)  = GND
  DQ(53)  = M_G_DQ<52>
  VSS(9)  = GND
  DQ(49)  = M_G_DQ<48>
  VSS(8)  = GND
  DQS6N  = M_G_DQS_DN<6>
  DQS6P  = M_G_DQS_DP<6>
  VSS(7)  = GND
  DQ(55)  = M_G_DQ<54>
  VSS(6)  = GND
  DQ(51)  = M_G_DQ<50>
  VSS(5)  = GND
  DQ(61)  = M_G_DQ<60>
  VSS(4)  = GND
  DQ(57)  = M_G_DQ<56>
  VSS(3)  = GND
  DQS7N  = M_G_DQS_DN<7>
  DQS7P  = M_G_DQS_DP<7>
  VSS(2)  = GND
  DQ(63)  = M_G_DQ<62>
  VSS(1)  = GND
  DQ(59)  = M_G_DQ<58>
  VSS(0)  = GND
  VDDSPD  = PVPP_GHJ
  SDA  = SMB_DDR_GHJ_VPP_SDA
  VPP(1)  = PVPP_GHJ
  VPP(0)  = PVPP_GHJ
  VPP(2)  = PVPP_GHJ

(kicad_pcb
	(version 20260206)
	(generator "pcbnew")
	(generator_version "10.0")
	(general
		(thickness 1.6)
		(legacy_teardrops no)
	)
	(paper "A4")
	(title_block
		(title "Wiwynn_Tioga_Pass_MB.brd")
		(comment 1 "Tioga Pass / footprint 2018 of 4770 (J1G1), pads 250-291 of 291")
	)
	(layers
		(0 "F.Cu" signal "TOP")
		(4 "In1.Cu" signal "L2GND")
		(6 "In2.Cu" signal "L3")
		(8 "In3.Cu" signal "L4GND")
		(10 "In4.Cu" signal "L5")
		(12 "In5.Cu" signal "L6GND")
		(14 "In6.Cu" signal "L7VCC")
		(16 "In7.Cu" signal "L8VCC")
		(18 "In8.Cu" signal "L9GND")
		(20 "In9.Cu" signal "L10")
		(22 "In10.Cu" signal "L11GND")
		(24 "In11.Cu" signal "L12")
		(26 "In12.Cu" signal "L13GND")
		(2 "B.Cu" signal "BOTTOM")
		(9 "F.Adhes" user "F.Adhesive")
		(11 "B.Adhes" user "B.Adhesive")
		(13 "F.Paste" user "Package Geometry/Pastemask Top")
		(15 "B.Paste" user "Package Geometry/Pastemask Bottom")
		(5 "F.SilkS" user "Ref Des/Silkscreen Top")
		(7 "B.SilkS" user "Ref Des/Silkscreen Bottom")
		(1 "F.Mask" user "Board Geometry/Soldermask Top")
		(3 "B.Mask" user "Board Geometry/Soldermask Bottom")
		(17 "Dwgs.User" user "User.Drawings")
		(19 "Cmts.User" user "User.Comments")
		(21 "Eco1.User" user "User.Eco1")
		(23 "Eco2.User" user "User.Eco2")
		(25 "Edge.Cuts" user "Board Geometry/Outline")
		(27 "Margin" user)
		(31 "F.CrtYd" user "Package Geometry/Place Bound Top")
		(29 "B.CrtYd" user "Package Geometry/Place Bound Bottom")
		(35 "F.Fab" user "Ref Des/Assembly Top")
		(33 "B.Fab" user "Ref Des/Assembly Bottom")
	)
	(footprint ""
		(layer "F.Cu")
		(at 29.699458 -15.423642 90)
		(property "Reference" "J1G1"
			(at 9.314688 35.070542 0)
			(unlocked yes)
			(layer "F.SilkS")
			(effects
				(font
					(size 0.7874 0.5842)
					(thickness 0.1524)
				)
				(justify left)
			)
		)
		(property "Value" ""
			(at 0 0 90)
			(layer "F.Fab")
			(effects
				(font
					(size 1.27 1.27)
				)
			)
		)
		(duplicate_pad_numbers_are_jumpers no)
		(pad "247" smd rect
			(at 4.59994 91.799918 90)
			(size 1.8034 0.508)
			(layers "F.Cu" "F.Mask" "F.Paste")
			(net "M_G_DQ<38>")
		)
		(pad "248" smd rect
			(at 4.59994 92.650056 90)
			(size 1.8034 0.508)
			(layers "F.Cu" "F.Mask" "F.Paste")
			(net "GND")
		)
		(pad "249" smd rect
			(at 4.59994 93.49994 90)
			(size 1.8034 0.508)
			(layers "F.Cu" "F.Mask" "F.Paste")
			(net "M_G_DQ<34>")
		)
		(pad "250" smd rect
			(at 4.59994 94.350078 90)
			(size 1.8034 0.508)
			(layers "F.Cu" "F.Mask" "F.Paste")
			(net "GND")
		)
		(pad "251" smd rect
			(at 4.59994 95.199962 90)
			(size 1.8034 0.508)
			(layers "F.Cu" "F.Mask" "F.Paste")
			(net "M_G_DQ<44>")
		)
		(pad "252" smd rect
			(at 4.59994 96.0501 90)
			(size 1.8034 0.508)
			(layers "F.Cu" "F.Mask" "F.Paste")
			(net "GND")
		)
		(pad "253" smd rect
			(at 4.59994 96.899984 90)
			(size 1.8034 0.508)
			(layers "F.Cu" "F.Mask" "F.Paste")
			(net "M_G_DQ<40>")
		)
		(pad "254" smd rect
			(at 4.59994 97.750122 90)
			(size 1.8034 0.508)
			(layers "F.Cu" "F.Mask" "F.Paste")
			(net "GND")
		)
		(pad "255" smd rect
			(at 4.59994 98.600006 90)
			(size 1.8034 0.508)
			(layers "F.Cu" "F.Mask" "F.Paste")
			(net "M_G_DQS_DN<5>")
		)
		(pad "256" smd rect
			(at 4.59994 99.44989 90)
			(size 1.8034 0.508)
			(layers "F.Cu" "F.Mask" "F.Paste")
			(net "M_G_DQS_DP<5>")
		)
		(pad "257" smd rect
			(at 4.59994 100.300028 90)
			(size 1.8034 0.508)
			(layers "F.Cu" "F.Mask" "F.Paste")
			(net "GND")
		)
		(pad "258" smd rect
			(at 4.59994 101.149912 90)
			(size 1.8034 0.508)
			(layers "F.Cu" "F.Mask" "F.Paste")
			(net "M_G_DQ<46>")
		)
		(pad "259" smd rect
			(at 4.59994 102.00005 90)
			(size 1.8034 0.508)
			(layers "F.Cu" "F.Mask" "F.Paste")
			(net "GND")
		)
		(pad "260" smd rect
			(at 4.59994 102.849934 90)
			(size 1.8034 0.508)
			(layers "F.Cu" "F.Mask" "F.Paste")
			(net "M_G_DQ<42>")
		)
		(pad "261" smd rect
			(at 4.59994 103.700072 90)
			(size 1.8034 0.508)
			(layers "F.Cu" "F.Mask" "F.Paste")
			(net "GND")
		)
		(pad "262" smd rect
			(at 4.59994 104.549956 90)
			(size 1.8034 0.508)
			(layers "F.Cu" "F.Mask" "F.Paste")
			(net "M_G_DQ<52>")
		)
		(pad "263" smd rect
			(at 4.59994 105.400094 90)
			(size 1.8034 0.508)
			(layers "F.Cu" "F.Mask" "F.Paste")
			(net "GND")
		)
		(pad "264" smd rect
			(at 4.59994 106.249978 90)
			(size 1.8034 0.508)
			(layers "F.Cu" "F.Mask" "F.Paste")
			(net "M_G_DQ<48>")
		)
		(pad "265" smd rect
			(at 4.59994 107.100116 90)
			(size 1.8034 0.508)
			(layers "F.Cu" "F.Mask" "F.Paste")
			(net "GND")
		)
		(pad "266" smd rect
			(at 4.59994 107.95 90)
			(size 1.8034 0.508)
			(layers "F.Cu" "F.Mask" "F.Paste")
			(net "M_G_DQS_DN<6>")
		)
		(pad "267" smd rect
			(at 4.59994 108.799884 90)
			(size 1.8034 0.508)
			(layers "F.Cu" "F.Mask" "F.Paste")
			(net "M_G_DQS_DP<6>")
		)
		(pad "268" smd rect
			(at 4.59994 109.650022 90)
			(size 1.8034 0.508)
			(layers "F.Cu" "F.Mask" "F.Paste")
			(net "GND")
		)
		(pad "269" smd rect
			(at 4.59994 110.499906 90)
			(size 1.8034 0.508)
			(layers "F.Cu" "F.Mask" "F.Paste")
			(net "M_G_DQ<54>")
		)
		(pad "270" smd rect
			(at 4.59994 111.350044 90)
			(size 1.8034 0.508)
			(layers "F.Cu" "F.Mask" "F.Paste")
			(net "GND")
		)
		(pad "271" smd rect
			(at 4.59994 112.199928 90)
			(size 1.8034 0.508)
			(layers "F.Cu" "F.Mask" "F.Paste")
			(net "M_G_DQ<50>")
		)
		(pad "272" smd rect
			(at 4.59994 113.050066 90)
			(size 1.8034 0.508)
			(layers "F.Cu" "F.Mask" "F.Paste")
			(net "GND")
		)
		(pad "273" smd rect
			(at 4.59994 113.89995 90)
			(size 1.8034 0.508)
			(layers "F.Cu" "F.Mask" "F.Paste")
			(net "M_G_DQ<60>")
		)
		(pad "274" smd rect
			(at 4.59994 114.750088 90)
			(size 1.8034 0.508)
			(layers "F.Cu" "F.Mask" "F.Paste")
			(net "GND")
		)
		(pad "275" smd rect
			(at 4.59994 115.599972 90)
			(size 1.8034 0.508)
			(layers "F.Cu" "F.Mask" "F.Paste")
			(net "M_G_DQ<56>")
		)
		(pad "276" smd rect
			(at 4.59994 116.45011 90)
			(size 1.8034 0.508)
			(layers "F.Cu" "F.Mask" "F.Paste")
			(net "GND")
		)
		(pad "277" smd rect
			(at 4.59994 117.299994 90)
			(size 1.8034 0.508)
			(layers "F.Cu" "F.Mask" "F.Paste")
			(net "M_G_DQS_DN<7>")
		)
		(pad "278" smd rect
			(at 4.59994 118.149878 90)
			(size 1.8034 0.508)
			(layers "F.Cu" "F.Mask" "F.Paste")
			(net "M_G_DQS_DP<7>")
		)
		(pad "279" smd rect
			(at 4.59994 119.000016 90)
			(size 1.8034 0.508)
			(layers "F.Cu" "F.Mask" "F.Paste")
			(net "GND")
		)
		(pad "280" smd rect
			(at 4.59994 119.8499 90)
			(size 1.8034 0.508)
			(layers "F.Cu" "F.Mask" "F.Paste")
			(net "M_G_DQ<62>")
		)
		(pad "281" smd rect
			(at 4.59994 120.700038 90)
			(size 1.8034 0.508)
			(layers "F.Cu" "F.Mask" "F.Paste")
			(net "GND")
		)
		(pad "282" smd rect
			(at 4.59994 121.549922 90)
			(size 1.8034 0.508)
			(layers "F.Cu" "F.Mask" "F.Paste")
			(net "M_G_DQ<58>")
		)
		(pad "283" smd rect
			(at 4.59994 122.40006 90)
			(size 1.8034 0.508)
			(layers "F.Cu" "F.Mask" "F.Paste")
			(net "GND")
		)
		(pad "284" smd rect
			(at 4.59994 123.249944 90)
			(size 1.8034 0.508)
			(layers "F.Cu" "F.Mask" "F.Paste")
			(net "PVPP_GHJ")
		)
		(pad "285" smd rect
			(at 4.59994 124.100082 90)
			(size 1.8034 0.508)
			(layers "F.Cu" "F.Mask" "F.Paste")
			(net "SMB_DDR_GHJ_VPP_SDA")
		)
		(pad "286" smd rect
			(at 4.59994 124.949966 90)
			(size 1.8034 0.508)
			(layers "F.Cu" "F.Mask" "F.Paste")
			(net "PVPP_GHJ")
		)
		(pad "287" smd rect
			(at 4.59994 125.800104 90)
			(size 1.8034 0.508)
			(layers "F.Cu" "F.Mask" "F.Paste")
			(net "PVPP_GHJ")
		)
		(pad "288" smd rect
			(at 4.59994 126.649988 90)
			(size 1.8034 0.508)
			(layers "F.Cu" "F.Mask" "F.Paste")
			(net "PVPP_GHJ")
		)
	)
)
